# T6G (Grand Teton) — schematic netlist excerpt (pin names and nets, part order shuffled) for the footprints in the layout excerpt that follows; sources: Cadence DE-HDL packaged netlist, KiCad conversion of 04192023_DAF0TMB3IC0_F0TG_MB_C_brd_V02_OCP.brd

X8027  TP_TDR_4P_FTS  TP_TDR_4P_DIP EMPTY  pkg TH  page 260
  S1  = TDR_DIFF_85_IN5_DN
  P1  = T1_GND
  P2  = T1_GND
  S2  = TDR_DIFF_85_IN5_DP

PR414  Q_RES  1K 1% CHIP  pkg 0402LF  page 208 : A = PVDD11_S3_P0 ; B = GND

(kicad_pcb
	(version 20260206)
	(generator "pcbnew")
	(generator_version "10.0")
	(general
		(thickness 1.6)
		(legacy_teardrops no)
	)
	(paper "A4")
	(title_block
		(title "04192023_DAF0TMB3IC0_F0TG_MB_C_brd_V02_OCP.brd")
		(comment 1 "Grand Teton / footprints 7757-7758 of 8354")
	)
	(layers
		(0 "F.Cu" signal "TOP")
		(4 "In1.Cu" signal "GND")
		(6 "In2.Cu" signal "IN1")
		(8 "In3.Cu" signal "GND1")
		(10 "In4.Cu" signal "IN2")
		(12 "In5.Cu" signal "GND2")
		(14 "In6.Cu" signal "IN3")
		(16 "In7.Cu" signal "GND3")
		(18 "In8.Cu" signal "VCC")
		(20 "In9.Cu" signal "VCC1")
		(22 "In10.Cu" signal "GND4")
		(24 "In11.Cu" signal "IN4")
		(26 "In12.Cu" signal "GND5")
		(28 "In13.Cu" signal "IN5")
		(30 "In14.Cu" signal "GND6")
		(32 "In15.Cu" signal "IN6")
		(34 "In16.Cu" signal "GND7")
		(2 "B.Cu" signal "BOTTOM")
		(9 "F.Adhes" user "F.Adhesive")
		(11 "B.Adhes" user "B.Adhesive")
		(13 "F.Paste" user "Package Geometry/Pastemask Top")
		(15 "B.Paste" user "Package Geometry/Pastemask Bottom")
		(5 "F.SilkS" user "Ref Des/Silkscreen Top")
		(7 "B.SilkS" user "Ref Des/Silkscreen Bottom")
		(1 "F.Mask" user "Board Geometry/Soldermask Top")
		(3 "B.Mask" user "Board Geometry/Soldermask Bottom")
		(17 "Dwgs.User" user "User.Drawings")
		(19 "Cmts.User" user "User.Comments")
		(21 "Eco1.User" user "User.Eco1")
		(23 "Eco2.User" user "User.Eco2")
		(25 "Edge.Cuts" user "Board Geometry/Outline")
		(27 "Margin" user)
		(31 "F.CrtYd" user "Package Geometry/Place Bound Top")
		(29 "B.CrtYd" user "Package Geometry/Place Bound Bottom")
		(35 "F.Fab" user "Ref Des/Assembly Top")
		(33 "B.Fab" user "Ref Des/Assembly Bottom")
	)
	(footprint ""
		(layer "B.Cu")
		(at 506.598428 -142.846806 -90)
		(property "Reference" "X8027"
			(at 4.4577 -1.50495 270)
			(unlocked yes)
			(layer "B.SilkS")
			(effects
				(font
					(size 0.7874 0.5842)
					(thickness 0.1524)
				)
				(justify left mirror)
			)
		)
		(property "Value" ""
			(at 0 0 90)
			(layer "B.Fab")
			(effects
				(font
					(size 1.27 1.27)
				)
				(justify mirror)
			)
		)
		(property "Device Type" "TP_TDR_4P_FTS_TH-TP_TDR_4P_DIP,EMPTY,TP15"
			(at -1.30175 1.27 180)
			(unlocked yes)
			(layer "B.Fab")
			(hide yes)
			(effects
				(font
					(size 0.635 0.4064)
					(thickness 0.1524)
				)
				(justify mirror)
			)
		)
		(property "User Part Number" "N_A"
			(at -1.30175 1.27 180)
			(unlocked yes)
			(layer "Cmts.User")
			(hide yes)
			(effects
				(font
					(size 0.635 0.4064)
					(thickness 0.1524)
				)
				(justify mirror)
			)
		)
		(duplicate_pad_numbers_are_jumpers no)
		(fp_line
			(start -2.54 3.81)
			(end -2.54 3.6703)
			(stroke
				(width 0.1524)
				(type default)
			)
			(layer "B.SilkS")
		)
		(fp_line
			(start 0 3.81)
			(end -2.54 3.81)
			(stroke
				(width 0.1524)
				(type default)
			)
			(layer "B.SilkS")
		)
		(fp_line
			(start 0 3.175)
			(end 0 3.81)
			(stroke
				(width 0.1524)
				(type default)
			)
			(layer "B.SilkS")
		)
		(fp_line
			(start -2.54 1.4097)
			(end -2.54 1.1303)
			(stroke
				(width 0.1524)
				(type default)
			)
			(layer "B.SilkS")
		)
		(fp_line
			(start 0 0.635)
			(end 0 1.905)
			(stroke
				(width 0.1524)
				(type default)
			)
			(layer "B.SilkS")
		)
		(fp_line
			(start -2.54 -1.1303)
			(end -2.54 -1.27)
			(stroke
				(width 0.1524)
				(type default)
			)
			(layer "B.SilkS")
		)
		(fp_line
			(start -2.54 -1.27)
			(end 0 -1.27)
			(stroke
				(width 0.1524)
				(type default)
			)
			(layer "B.SilkS")
		)
		(fp_line
			(start 0 -1.27)
			(end 0 -0.635)
			(stroke
				(width 0.1524)
				(type default)
			)
			(layer "B.SilkS")
		)
		(fp_poly
			(pts
				(xy 0.761746 0) (xy 2.285746 -0.762) (xy 2.285746 0.762)
			)
			(stroke
				(width 0)
				(type default)
			)
			(fill yes)
			(layer "B.SilkS")
		)
		(fp_line
			(start -2.54 3.81)
			(end -2.54 -1.27)
			(stroke
				(width 0.1)
				(type default)
			)
			(layer "B.Fab")
		)
		(fp_line
			(start 0 3.81)
			(end -2.54 3.81)
			(stroke
				(width 0.1)
				(type default)
			)
			(layer "B.Fab")
		)
		(fp_line
			(start -2.54 -1.27)
			(end 0 -1.27)
			(stroke
				(width 0.1)
				(type default)
			)
			(layer "B.Fab")
		)
		(fp_line
			(start 0 -1.27)
			(end 0 3.81)
			(stroke
				(width 0.1)
				(type default)
			)
			(layer "B.Fab")
		)
		(fp_poly
			(pts
				(xy 0.761746 0) (xy 2.285746 -0.762) (xy 2.285746 0.762)
			)
			(stroke
				(width 0)
				(type default)
			)
			(fill yes)
			(layer "B.Fab")
		)
		(pad "1" thru_hole circle
			(at 0 0 90)
			(size 1.0033 1.0033)
			(drill 0.249936)
			(layers "*.Cu" "*.Mask")
			(remove_unused_layers no)
			(net "TDR_DIFF_85_IN5_DN")
			(clearance 0.10795)
			(padstack
				(mode front_inner_back)
				(layer "Inner"
					(shape circle)
					(size 0.8001 0.8001)
					(clearance 0.1524)
				)
				(layer "B.Cu"
					(shape circle)
					(size 1.0033 1.0033)
					(thermal_gap 0.10795)
					(clearance 0.10795)
				)
			)
		)
		(pad "2" thru_hole circle
			(at -2.54 0 90)
			(size 1.9939 1.9939)
			(drill 0.249936)
			(layers "*.Cu" "*.Mask")
			(remove_unused_layers no)
			(net "T1_GND")
			(clearance 0.10795)
			(padstack
				(mode front_inner_back)
				(layer "Inner"
					(shape circle)
					(size 0.8001 0.8001)
					(clearance 0.1524)
				)
				(layer "B.Cu"
					(shape circle)
					(size 1.9939 1.9939)
					(thermal_gap 0.10795)
					(clearance 0.10795)
				)
			)
		)
		(pad "3" thru_hole circle
			(at -2.54 2.54 90)
			(size 1.9939 1.9939)
			(drill 0.249936)
			(layers "*.Cu" "*.Mask")
			(remove_unused_layers no)
			(net "T1_GND")
			(clearance 0.10795)
			(padstack
				(mode front_inner_back)
				(layer "Inner"
					(shape circle)
					(size 0.8001 0.8001)
					(clearance 0.1524)
				)
				(layer "B.Cu"
					(shape circle)
					(size 1.9939 1.9939)
					(thermal_gap 0.10795)
					(clearance 0.10795)
				)
			)
		)
		(pad "4" thru_hole circle
			(at 0 2.54 90)
			(size 1.0033 1.0033)
			(drill 0.249936)
			(layers "*.Cu" "*.Mask")
			(remove_unused_layers no)
			(net "TDR_DIFF_85_IN5_DP")
			(clearance 0.10795)
			(padstack
				(mode front_inner_back)
				(layer "Inner"
					(shape circle)
					(size 0.8001 0.8001)
					(clearance 0.1524)
				)
				(layer "B.Cu"
					(shape circle)
					(size 1.0033 1.0033)
					(thermal_gap 0.10795)
					(clearance 0.10795)
				)
			)
		)
	)
	(footprint ""
		(layer "B.Cu")
		(at 426.757338 -332.627732 90)
		(property "Reference" "PR414"
			(at 0 0 90)
			(layer "B.SilkS")
			(hide yes)
			(effects
				(font
					(size 1.27 1.27)
				)
				(justify mirror)
			)
		)
		(property "Value" ""
			(at 0 0 90)
			(layer "B.Fab")
			(effects
				(font
					(size 1.27 1.27)
				)
				(justify mirror)
			)
		)
		(duplicate_pad_numbers_are_jumpers no)
		(fp_line
			(start 0.7874 -0.4064)
			(end -0.7874 -0.4064)
			(stroke
				(width 0.1524)
				(type default)
			)
			(layer "B.SilkS")
		)
		(fp_line
			(start -0.7874 -0.4064)
			(end -0.7874 0.4064)
			(stroke
				(width 0.1524)
				(type default)
			)
			(layer "B.SilkS")
		)
		(fp_line
			(start 0.7874 0.4064)
			(end 0.7874 -0.4064)
			(stroke
				(width 0.1524)
				(type default)
			)
			(layer "B.SilkS")
		)
		(fp_line
			(start -0.7874 0.4064)
			(end 0.7874 0.4064)
			(stroke
				(width 0.1524)
				(type default)
			)
			(layer "B.SilkS")
		)
		(fp_line
			(start 0.67945 -0.305054)
			(end 0.12065 -0.305054)
			(stroke
				(width 0.1)
				(type default)
			)
			(layer "B.Fab")
		)
		(fp_line
			(start 0.12065 -0.305054)
			(end 0.12065 -0.2794)
			(stroke
				(width 0.1)
				(type default)
			)
			(layer "B.Fab")
		)
		(fp_line
			(start -0.12065 -0.3048)
			(end -0.67945 -0.3048)
			(stroke
				(width 0.1)
				(type default)
			)
			(layer "B.Fab")
		)
		(fp_line
			(start -0.67945 -0.3048)
			(end -0.67945 0.3048)
			(stroke
				(width 0.1)
				(type default)
			)
			(layer "B.Fab")
		)
		(fp_line
			(start 0.12065 -0.2794)
			(end -0.12065 -0.2794)
			(stroke
				(width 0.1)
				(type default)
			)
			(layer "B.Fab")
		)
		(fp_line
			(start -0.12065 -0.2794)
			(end -0.12065 -0.3048)
			(stroke
				(width 0.1)
				(type default)
			)
			(layer "B.Fab")
		)
		(fp_line
			(start 0.12065 0.2794)
			(end 0.12065 0.3048)
			(stroke
				(width 0.1)
				(type default)
			)
			(layer "B.Fab")
		)
		(fp_line
			(start -0.120396 0.2794)
			(end 0.12065 0.2794)
			(stroke
				(width 0.1)
				(type default)
			)
			(layer "B.Fab")
		)
		(fp_line
			(start 0.67945 0.3048)
			(end 0.67945 -0.305054)
			(stroke
				(width 0.1)
				(type default)
			)
			(layer "B.Fab")
		)
		(fp_line
			(start 0.12065 0.3048)
			(end 0.67945 0.3048)
			(stroke
				(width 0.1)
				(type default)
			)
			(layer "B.Fab")
		)
		(fp_line
			(start -0.120396 0.3048)
			(end -0.120396 0.2794)
			(stroke
				(width 0.1)
				(type default)
			)
			(layer "B.Fab")
		)
		(fp_line
			(start -0.67945 0.3048)
			(end -0.120396 0.3048)
			(stroke
				(width 0.1)
				(type default)
			)
			(layer "B.Fab")
		)
		(pad "1" smd circle
			(at 0.40005 0 270)
			(size 0 0)
			(layers "B.Cu" "B.Mask" "B.Paste")
			(net "PVDD11_S3_P0")
		)
		(pad "2" smd circle
			(at -0.40005 0 270)
			(size 0 0)
			(layers "B.Cu" "B.Mask" "B.Paste")
			(net "GND")
		)
	)
)
